FILE_TYPE = MULTI_PHYS_TABLE;
PART 'CONN6_C74770005'
{========================================================================================}
:PACK_TYPE |MATERIAL  |PART_NUMBER      = EnvComp                  | PART_NUMBER  | JEDEC_TYPE            | CLASS | DESCRIPTION                                |HEIGHT      |COMPONENT_TYPE  |LEAD_LENGTH  | SPEED_URL | Status |RPL| AML | Bus_Unit | Days ;
{========================================================================================}
'THLF'     | 'HDR'    | 'C74770-005'(!) = 'YES;YES;CNC;CNC;ok;CIP' | 'C74770-005' | 'CONN6_C74770005'     | 'IO'  | '1X6 HDR'                                  | '0.421 IN' | 'THMT'         | '0.138'     | 'http://speed.intel.com:8081/speed/module/pdm/item/pdm_item_detail_direct.asp?item_cde=C74770-005&item_rev=01&url_param=unused' | 'Design' | 'NO' | '2' | 'SMO_BOARDS' | '56' 
'THLF'     | 'EMPTY'  | 'C74770-005'(!) = 'YES;YES;CNC;CNC;ok;CIP' | 'C74770-005' | 'CONN6_C74770005'     | 'IO'  | '1X6 HDR'                                  | '0.421 IN' | 'THMT'         | '0.138'     | 'http://speed.intel.com:8081/speed/module/pdm/item/pdm_item_detail_direct.asp?item_cde=C74770-005&item_rev=01&url_param=unused' | 'Design' | 'NO' | '2' | 'SMO_BOARDS' | '56' 
'PIP'      | 'HDR'    | 'C74770-005'(!) = ''                       | 'C74770-005' | 'CONN6_C74770005_PIP' | 'IO'  | 'CONN,HDR,1 X 6,PLG,VT,0.1,093ST,KP SHR'   | '0.421 IN' | 'THMT'         | '0.138'     | 'http://speed.intel.com:8081/speed/module/pdm/item/pdm_item_detail_direct.asp?item_cde=C74770-005&item_rev=01&url_param=unused' | '' | '' | '' | '' | '' 
'PIP'      | 'EMPTY'  | 'C74770-005'(!) = ''                       | 'C74770-005' | 'CONN6_C74770005_PIP' | 'IO'  | 'CONN,HDR,1 X 6,PLG,VT,0.1,093ST,KP SHR'   | '0.421 IN' | 'THMT'         | '0.138'     | 'http://speed.intel.com:8081/speed/module/pdm/item/pdm_item_detail_direct.asp?item_cde=C74770-005&item_rev=01&url_param=unused' | '' | '' | '' | '' | '' 
END_PART
END.
